(kicad_pcb
	(version 20260206)
	(generator "pcbnew")
	(generator_version "10.0")
	(general
		(thickness 1.6)
		(legacy_teardrops no)
	)
	(paper "A4")
	(title_block
		(title "01162023_DA0F0TEBIF0_F0T_Expander_BD_F_brd_V02_OCP.brd")
		(comment 1 "Grand Teton / footprints 7796-7804 of 9728")
	)
	(layers
		(0 "F.Cu" signal "TOP")
		(4 "In1.Cu" signal "GND")
		(6 "In2.Cu" signal "VCC")
		(8 "In3.Cu" signal "VCC1")
		(10 "In4.Cu" signal "GND1")
		(12 "In5.Cu" signal "IN1")
		(14 "In6.Cu" signal "GND2")
		(16 "In7.Cu" signal "IN2")
		(18 "In8.Cu" signal "GND3")
		(20 "In9.Cu" signal "IN3")
		(22 "In10.Cu" signal "GND4")
		(24 "In11.Cu" signal "IN4")
		(26 "In12.Cu" signal "GND5")
		(28 "In13.Cu" signal "IN5")
		(30 "In14.Cu" signal "GND6")
		(32 "In15.Cu" signal "IN6")
		(34 "In16.Cu" signal "GND7")
		(2 "B.Cu" signal "BOTTOM")
		(9 "F.Adhes" user "F.Adhesive")
		(11 "B.Adhes" user "B.Adhesive")
		(13 "F.Paste" user "Package Geometry/Pastemask Top")
		(15 "B.Paste" user "Package Geometry/Pastemask Bottom")
		(5 "F.SilkS" user "Ref Des/Silkscreen Top")
		(7 "B.SilkS" user "Ref Des/Silkscreen Bottom")
		(1 "F.Mask" user "Board Geometry/Soldermask Top")
		(3 "B.Mask" user "Board Geometry/Soldermask Bottom")
		(17 "Dwgs.User" user "User.Drawings")
		(19 "Cmts.User" user "User.Comments")
		(21 "Eco1.User" user "User.Eco1")
		(23 "Eco2.User" user "User.Eco2")
		(25 "Edge.Cuts" user "Board Geometry/Outline")
		(27 "Margin" user)
		(31 "F.CrtYd" user "Package Geometry/Place Bound Top")
		(29 "B.CrtYd" user "Package Geometry/Place Bound Bottom")
		(35 "F.Fab" user "Ref Des/Assembly Top")
		(33 "B.Fab" user "Ref Des/Assembly Bottom")
	)
	(footprint ""
		(layer "B.Cu")
		(at 276.649688 -295.89984)
		(property "Reference" "C3352"
			(at 0 0 0)
			(layer "B.SilkS")
			(hide yes)
			(effects
				(font
					(size 1.27 1.27)
				)
				(justify mirror)
			)
		)
		(property "Value" ""
			(at 0 0 0)
			(layer "B.Fab")
			(effects
				(font
					(size 1.27 1.27)
				)
				(justify mirror)
			)
		)
		(duplicate_pad_numbers_are_jumpers no)
		(fp_line
			(start -0.299974 -0.150114)
			(end -0.299974 0.150114)
			(stroke
				(width 0.1)
				(type default)
			)
			(layer "B.Fab")
		)
		(fp_line
			(start -0.299974 0.150114)
			(end 0.299974 0.150114)
			(stroke
				(width 0.1)
				(type default)
			)
			(layer "B.Fab")
		)
		(fp_line
			(start 0.299974 -0.150114)
			(end -0.299974 -0.150114)
			(stroke
				(width 0.1)
				(type default)
			)
			(layer "B.Fab")
		)
		(fp_line
			(start 0.299974 0.150114)
			(end 0.299974 -0.150114)
			(stroke
				(width 0.1)
				(type default)
			)
			(layer "B.Fab")
		)
		(pad "1" smd rect
			(at 0.2667 0 180)
			(size 0.3048 0.381)
			(layers "B.Cu" "B.Mask" "B.Paste")
			(net "P1V8_PEX")
		)
		(pad "2" smd rect
			(at -0.2667 0 180)
			(size 0.3048 0.381)
			(layers "B.Cu" "B.Mask" "B.Paste")
			(net "GND")
		)
	)
	(footprint ""
		(layer "B.Cu")
		(at 225.564954 -145.169128 180)
		(property "Reference" "C2798"
			(at 0 0 0)
			(layer "B.SilkS")
			(hide yes)
			(effects
				(font
					(size 1.27 1.27)
				)
				(justify mirror)
			)
		)
		(property "Value" ""
			(at 0 0 0)
			(layer "B.Fab")
			(effects
				(font
					(size 1.27 1.27)
				)
				(justify mirror)
			)
		)
		(duplicate_pad_numbers_are_jumpers no)
		(fp_line
			(start 0.7874 0.4064)
			(end 0.7874 -0.4064)
			(stroke
				(width 0.1524)
				(type default)
			)
			(layer "B.SilkS")
		)
		(fp_line
			(start 0.7874 -0.4064)
			(end -0.7874 -0.4064)
			(stroke
				(width 0.1524)
				(type default)
			)
			(layer "B.SilkS")
		)
		(fp_line
			(start -0.7874 0.4064)
			(end 0.7874 0.4064)
			(stroke
				(width 0.1524)
				(type default)
			)
			(layer "B.SilkS")
		)
		(fp_line
			(start -0.7874 -0.4064)
			(end -0.7874 0.4064)
			(stroke
				(width 0.1524)
				(type default)
			)
			(layer "B.SilkS")
		)
		(fp_line
			(start 0.67945 0.3048)
			(end 0.67945 -0.305054)
			(stroke
				(width 0.1)
				(type default)
			)
			(layer "B.Fab")
		)
		(fp_line
			(start 0.67945 -0.305054)
			(end 0.12065 -0.305054)
			(stroke
				(width 0.1)
				(type default)
			)
			(layer "B.Fab")
		)
		(fp_line
			(start 0.12065 0.3048)
			(end 0.67945 0.3048)
			(stroke
				(width 0.1)
				(type default)
			)
			(layer "B.Fab")
		)
		(fp_line
			(start 0.12065 0.2794)
			(end 0.12065 0.3048)
			(stroke
				(width 0.1)
				(type default)
			)
			(layer "B.Fab")
		)
		(fp_line
			(start 0.12065 -0.2794)
			(end -0.12065 -0.2794)
			(stroke
				(width 0.1)
				(type default)
			)
			(layer "B.Fab")
		)
		(fp_line
			(start 0.12065 -0.305054)
			(end 0.12065 -0.2794)
			(stroke
				(width 0.1)
				(type default)
			)
			(layer "B.Fab")
		)
		(fp_line
			(start -0.120396 0.3048)
			(end -0.120396 0.2794)
			(stroke
				(width 0.1)
				(type default)
			)
			(layer "B.Fab")
		)
		(fp_line
			(start -0.120396 0.2794)
			(end 0.12065 0.2794)
			(stroke
				(width 0.1)
				(type default)
			)
			(layer "B.Fab")
		)
		(fp_line
			(start -0.12065 -0.2794)
			(end -0.12065 -0.3048)
			(stroke
				(width 0.1)
				(type default)
			)
			(layer "B.Fab")
		)
		(fp_line
			(start -0.12065 -0.3048)
			(end -0.67945 -0.3048)
			(stroke
				(width 0.1)
				(type default)
			)
			(layer "B.Fab")
		)
		(fp_line
			(start -0.67945 0.3048)
			(end -0.120396 0.3048)
			(stroke
				(width 0.1)
				(type default)
			)
			(layer "B.Fab")
		)
		(fp_line
			(start -0.67945 -0.3048)
			(end -0.67945 0.3048)
			(stroke
				(width 0.1)
				(type default)
			)
			(layer "B.Fab")
		)
		(pad "1" smd circle
			(at 0.40005 0)
			(size 0 0)
			(layers "B.Cu" "B.Mask" "B.Paste")
			(net "P3V3_CLK_GEN_VDDA25M_CK440_PEX")
		)
		(pad "2" smd circle
			(at -0.40005 0)
			(size 0 0)
			(layers "B.Cu" "B.Mask" "B.Paste")
			(net "GND")
		)
	)
	(footprint ""
		(layer "B.Cu")
		(at 421.700198 -109.251496)
		(property "Reference" "C953"
			(at 0 0 0)
			(layer "B.SilkS")
			(hide yes)
			(effects
				(font
					(size 1.27 1.27)
				)
				(justify mirror)
			)
		)
		(property "Value" ""
			(at 0 0 0)
			(layer "B.Fab")
			(effects
				(font
					(size 1.27 1.27)
				)
				(justify mirror)
			)
		)
		(duplicate_pad_numbers_are_jumpers no)
		(fp_line
			(start -0.299974 -0.150114)
			(end -0.299974 0.150114)
			(stroke
				(width 0.1)
				(type default)
			)
			(layer "B.Fab")
		)
		(fp_line
			(start -0.299974 0.150114)
			(end 0.299974 0.150114)
			(stroke
				(width 0.1)
				(type default)
			)
			(layer "B.Fab")
		)
		(fp_line
			(start 0.299974 -0.150114)
			(end -0.299974 -0.150114)
			(stroke
				(width 0.1)
				(type default)
			)
			(layer "B.Fab")
		)
		(fp_line
			(start 0.299974 0.150114)
			(end 0.299974 -0.150114)
			(stroke
				(width 0.1)
				(type default)
			)
			(layer "B.Fab")
		)
		(pad "1" smd rect
			(at 0.2667 0 180)
			(size 0.3048 0.381)
			(layers "B.Cu" "B.Mask" "B.Paste")
			(net "P12V_NIC7")
		)
		(pad "2" smd rect
			(at -0.2667 0 180)
			(size 0.3048 0.381)
			(layers "B.Cu" "B.Mask" "B.Paste")
			(net "GND")
		)
	)
	(footprint ""
		(layer "B.Cu")
		(at 345.76131 -258.004564 90)
		(property "Reference" "PR145"
			(at 0 0 90)
			(layer "B.SilkS")
			(hide yes)
			(effects
				(font
					(size 1.27 1.27)
				)
				(justify mirror)
			)
		)
		(property "Value" ""
			(at 0 0 90)
			(layer "B.Fab")
			(effects
				(font
					(size 1.27 1.27)
				)
				(justify mirror)
			)
		)
		(duplicate_pad_numbers_are_jumpers no)
		(fp_line
			(start 0.7874 -0.4064)
			(end -0.7874 -0.4064)
			(stroke
				(width 0.1524)
				(type default)
			)
			(layer "B.SilkS")
		)
		(fp_line
			(start -0.7874 -0.4064)
			(end -0.7874 0.4064)
			(stroke
				(width 0.1524)
				(type default)
			)
			(layer "B.SilkS")
		)
		(fp_line
			(start 0.7874 0.4064)
			(end 0.7874 -0.4064)
			(stroke
				(width 0.1524)
				(type default)
			)
			(layer "B.SilkS")
		)
		(fp_line
			(start -0.7874 0.4064)
			(end 0.7874 0.4064)
			(stroke
				(width 0.1524)
				(type default)
			)
			(layer "B.SilkS")
		)
		(fp_line
			(start 0.67945 -0.305054)
			(end 0.12065 -0.305054)
			(stroke
				(width 0.1)
				(type default)
			)
			(layer "B.Fab")
		)
		(fp_line
			(start 0.12065 -0.305054)
			(end 0.12065 -0.2794)
			(stroke
				(width 0.1)
				(type default)
			)
			(layer "B.Fab")
		)
		(fp_line
			(start -0.12065 -0.3048)
			(end -0.67945 -0.3048)
			(stroke
				(width 0.1)
				(type default)
			)
			(layer "B.Fab")
		)
		(fp_line
			(start -0.67945 -0.3048)
			(end -0.67945 0.3048)
			(stroke
				(width 0.1)
				(type default)
			)
			(layer "B.Fab")
		)
		(fp_line
			(start 0.12065 -0.2794)
			(end -0.12065 -0.2794)
			(stroke
				(width 0.1)
				(type default)
			)
			(layer "B.Fab")
		)
		(fp_line
			(start -0.12065 -0.2794)
			(end -0.12065 -0.3048)
			(stroke
				(width 0.1)
				(type default)
			)
			(layer "B.Fab")
		)
		(fp_line
			(start 0.12065 0.2794)
			(end 0.12065 0.3048)
			(stroke
				(width 0.1)
				(type default)
			)
			(layer "B.Fab")
		)
		(fp_line
			(start -0.120396 0.2794)
			(end 0.12065 0.2794)
			(stroke
				(width 0.1)
				(type default)
			)
			(layer "B.Fab")
		)
		(fp_line
			(start 0.67945 0.3048)
			(end 0.67945 -0.305054)
			(stroke
				(width 0.1)
				(type default)
			)
			(layer "B.Fab")
		)
		(fp_line
			(start 0.12065 0.3048)
			(end 0.67945 0.3048)
			(stroke
				(width 0.1)
				(type default)
			)
			(layer "B.Fab")
		)
		(fp_line
			(start -0.120396 0.3048)
			(end -0.120396 0.2794)
			(stroke
				(width 0.1)
				(type default)
			)
			(layer "B.Fab")
		)
		(fp_line
			(start -0.67945 0.3048)
			(end -0.120396 0.3048)
			(stroke
				(width 0.1)
				(type default)
			)
			(layer "B.Fab")
		)
		(pad "1" smd circle
			(at 0.40005 0 270)
			(size 0 0)
			(layers "B.Cu" "B.Mask" "B.Paste")
			(net "P5V_AUX")
		)
		(pad "2" smd circle
			(at -0.40005 0 270)
			(size 0 0)
			(layers "B.Cu" "B.Mask" "B.Paste")
			(net "P0V8_PEX2_IINSEN")
		)
	)
	(footprint ""
		(layer "B.Cu")
		(at 167.200072 -301.599854 -90)
		(property "Reference" "C1443"
			(at 0 0 90)
			(layer "B.SilkS")
			(hide yes)
			(effects
				(font
					(size 1.27 1.27)
				)
				(justify mirror)
			)
		)
		(property "Value" ""
			(at 0 0 90)
			(layer "B.Fab")
			(effects
				(font
					(size 1.27 1.27)
				)
				(justify mirror)
			)
		)
		(duplicate_pad_numbers_are_jumpers no)
		(fp_line
			(start -0.299974 0.150114)
			(end 0.299974 0.150114)
			(stroke
				(width 0.1)
				(type default)
			)
			(layer "B.Fab")
		)
		(fp_line
			(start 0.299974 0.150114)
			(end 0.299974 -0.150114)
			(stroke
				(width 0.1)
				(type default)
			)
			(layer "B.Fab")
		)
		(fp_line
			(start -0.299974 -0.150114)
			(end -0.299974 0.150114)
			(stroke
				(width 0.1)
				(type default)
			)
			(layer "B.Fab")
		)
		(fp_line
			(start 0.299974 -0.150114)
			(end -0.299974 -0.150114)
			(stroke
				(width 0.1)
				(type default)
			)
			(layer "B.Fab")
		)
		(pad "1" smd rect
			(at 0.2667 0 90)
			(size 0.3048 0.381)
			(layers "B.Cu" "B.Mask" "B.Paste")
			(net "P0V8_SERDES_VDDA_PEX1")
		)
		(pad "2" smd rect
			(at -0.2667 0 90)
			(size 0.3048 0.381)
			(layers "B.Cu" "B.Mask" "B.Paste")
			(net "GND")
		)
	)
	(footprint ""
		(layer "B.Cu")
		(at 64.874902 -293.99992 90)
		(property "Reference" "C1144"
			(at 0 0 90)
			(layer "B.SilkS")
			(hide yes)
			(effects
				(font
					(size 1.27 1.27)
				)
				(justify mirror)
			)
		)
		(property "Value" ""
			(at 0 0 90)
			(layer "B.Fab")
			(effects
				(font
					(size 1.27 1.27)
				)
				(justify mirror)
			)
		)
		(duplicate_pad_numbers_are_jumpers no)
		(fp_line
			(start 0.299974 -0.150114)
			(end -0.299974 -0.150114)
			(stroke
				(width 0.1)
				(type default)
			)
			(layer "B.Fab")
		)
		(fp_line
			(start -0.299974 -0.150114)
			(end -0.299974 0.150114)
			(stroke
				(width 0.1)
				(type default)
			)
			(layer "B.Fab")
		)
		(fp_line
			(start 0.299974 0.150114)
			(end 0.299974 -0.150114)
			(stroke
				(width 0.1)
				(type default)
			)
			(layer "B.Fab")
		)
		(fp_line
			(start -0.299974 0.150114)
			(end 0.299974 0.150114)
			(stroke
				(width 0.1)
				(type default)
			)
			(layer "B.Fab")
		)
		(pad "1" smd rect
			(at 0.2667 0 270)
			(size 0.3048 0.381)
			(layers "B.Cu" "B.Mask" "B.Paste")
			(net "P0V8_PEX0")
		)
		(pad "2" smd rect
			(at -0.2667 0 270)
			(size 0.3048 0.381)
			(layers "B.Cu" "B.Mask" "B.Paste")
			(net "GND")
		)
	)
	(footprint ""
		(layer "B.Cu")
		(at 63.449962 -301.599854 -90)
		(property "Reference" "C1213"
			(at 0 0 90)
			(layer "B.SilkS")
			(hide yes)
			(effects
				(font
					(size 1.27 1.27)
				)
				(justify mirror)
			)
		)
		(property "Value" ""
			(at 0 0 90)
			(layer "B.Fab")
			(effects
				(font
					(size 1.27 1.27)
				)
				(justify mirror)
			)
		)
		(duplicate_pad_numbers_are_jumpers no)
		(fp_line
			(start -0.299974 0.150114)
			(end 0.299974 0.150114)
			(stroke
				(width 0.1)
				(type default)
			)
			(layer "B.Fab")
		)
		(fp_line
			(start 0.299974 0.150114)
			(end 0.299974 -0.150114)
			(stroke
				(width 0.1)
				(type default)
			)
			(layer "B.Fab")
		)
		(fp_line
			(start -0.299974 -0.150114)
			(end -0.299974 0.150114)
			(stroke
				(width 0.1)
				(type default)
			)
			(layer "B.Fab")
		)
		(fp_line
			(start 0.299974 -0.150114)
			(end -0.299974 -0.150114)
			(stroke
				(width 0.1)
				(type default)
			)
			(layer "B.Fab")
		)
		(pad "1" smd rect
			(at 0.2667 0 90)
			(size 0.3048 0.381)
			(layers "B.Cu" "B.Mask" "B.Paste")
			(net "P0V8_SERDES_VDDA_PEX0")
		)
		(pad "2" smd rect
			(at -0.2667 0 90)
			(size 0.3048 0.381)
			(layers "B.Cu" "B.Mask" "B.Paste")
			(net "GND")
		)
	)
	(footprint ""
		(layer "B.Cu")
		(at 224.763076 -200.984104 90)
		(property "Reference" "R461"
			(at 0 0 90)
			(layer "B.SilkS")
			(hide yes)
			(effects
				(font
					(size 1.27 1.27)
				)
				(justify mirror)
			)
		)
		(property "Value" ""
			(at 0 0 90)
			(layer "B.Fab")
			(effects
				(font
					(size 1.27 1.27)
				)
				(justify mirror)
			)
		)
		(duplicate_pad_numbers_are_jumpers no)
		(fp_line
			(start 0.7874 -0.4064)
			(end -0.7874 -0.4064)
			(stroke
				(width 0.1524)
				(type default)
			)
			(layer "B.SilkS")
		)
		(fp_line
			(start -0.7874 -0.4064)
			(end -0.7874 0.4064)
			(stroke
				(width 0.1524)
				(type default)
			)
			(layer "B.SilkS")
		)
		(fp_line
			(start 0.7874 0.4064)
			(end 0.7874 -0.4064)
			(stroke
				(width 0.1524)
				(type default)
			)
			(layer "B.SilkS")
		)
		(fp_line
			(start -0.7874 0.4064)
			(end 0.7874 0.4064)
			(stroke
				(width 0.1524)
				(type default)
			)
			(layer "B.SilkS")
		)
		(fp_line
			(start 0.67945 -0.305054)
			(end 0.12065 -0.305054)
			(stroke
				(width 0.1)
				(type default)
			)
			(layer "B.Fab")
		)
		(fp_line
			(start 0.12065 -0.305054)
			(end 0.12065 -0.2794)
			(stroke
				(width 0.1)
				(type default)
			)
			(layer "B.Fab")
		)
		(fp_line
			(start -0.12065 -0.3048)
			(end -0.67945 -0.3048)
			(stroke
				(width 0.1)
				(type default)
			)
			(layer "B.Fab")
		)
		(fp_line
			(start -0.67945 -0.3048)
			(end -0.67945 0.3048)
			(stroke
				(width 0.1)
				(type default)
			)
			(layer "B.Fab")
		)
		(fp_line
			(start 0.12065 -0.2794)
			(end -0.12065 -0.2794)
			(stroke
				(width 0.1)
				(type default)
			)
			(layer "B.Fab")
		)
		(fp_line
			(start -0.12065 -0.2794)
			(end -0.12065 -0.3048)
			(stroke
				(width 0.1)
				(type default)
			)
			(layer "B.Fab")
		)
		(fp_line
			(start 0.12065 0.2794)
			(end 0.12065 0.3048)
			(stroke
				(width 0.1)
				(type default)
			)
			(layer "B.Fab")
		)
		(fp_line
			(start -0.120396 0.2794)
			(end 0.12065 0.2794)
			(stroke
				(width 0.1)
				(type default)
			)
			(layer "B.Fab")
		)
		(fp_line
			(start 0.67945 0.3048)
			(end 0.67945 -0.305054)
			(stroke
				(width 0.1)
				(type default)
			)
			(layer "B.Fab")
		)
		(fp_line
			(start 0.12065 0.3048)
			(end 0.67945 0.3048)
			(stroke
				(width 0.1)
				(type default)
			)
			(layer "B.Fab")
		)
		(fp_line
			(start -0.120396 0.3048)
			(end -0.120396 0.2794)
			(stroke
				(width 0.1)
				(type default)
			)
			(layer "B.Fab")
		)
		(fp_line
			(start -0.67945 0.3048)
			(end -0.120396 0.3048)
			(stroke
				(width 0.1)
				(type default)
			)
			(layer "B.Fab")
		)
		(pad "1" smd circle
			(at 0.40005 0 270)
			(size 0 0)
			(layers "B.Cu" "B.Mask" "B.Paste")
			(net "SPI_BIC1_MISO")
		)
		(pad "2" smd circle
			(at -0.40005 0 270)
			(size 0 0)
			(layers "B.Cu" "B.Mask" "B.Paste")
			(net "SPI_BIC1_MISO_R")
		)
	)
	(footprint ""
		(layer "B.Cu")
		(at 282.824936 -286.399732 90)
		(property "Reference" "C3294"
			(at 0 0 90)
			(layer "B.SilkS")
			(hide yes)
			(effects
				(font
					(size 1.27 1.27)
				)
				(justify mirror)
			)
		)
		(property "Value" ""
			(at 0 0 90)
			(layer "B.Fab")
			(effects
				(font
					(size 1.27 1.27)
				)
				(justify mirror)
			)
		)
		(duplicate_pad_numbers_are_jumpers no)
		(fp_line
			(start 0.299974 -0.150114)
			(end -0.299974 -0.150114)
			(stroke
				(width 0.1)
				(type default)
			)
			(layer "B.Fab")
		)
		(fp_line
			(start -0.299974 -0.150114)
			(end -0.299974 0.150114)
			(stroke
				(width 0.1)
				(type default)
			)
			(layer "B.Fab")
		)
		(fp_line
			(start 0.299974 0.150114)
			(end 0.299974 -0.150114)
			(stroke
				(width 0.1)
				(type default)
			)
			(layer "B.Fab")
		)
		(fp_line
			(start -0.299974 0.150114)
			(end 0.299974 0.150114)
			(stroke
				(width 0.1)
				(type default)
			)
			(layer "B.Fab")
		)
		(pad "1" smd rect
			(at 0.2667 0 270)
			(size 0.3048 0.381)
			(layers "B.Cu" "B.Mask" "B.Paste")
			(net "P1V25_SERDES_VDDPLL_PEX2")
		)
		(pad "2" smd rect
			(at -0.2667 0 270)
			(size 0.3048 0.381)
			(layers "B.Cu" "B.Mask" "B.Paste")
			(net "GND")
		)
	)
)
